(kicad_pcb
	(version 20260206)
	(generator "pcbnew")
	(generator_version "10.0")
	(general
		(thickness 1.6)
		(legacy_teardrops no)
	)
	(paper "A4")
	(title_block
		(title "01162023_DA0F0TEBIF0_F0T_Expander_BD_F_brd_V02_OCP.brd")
		(comment 1 "Grand Teton / footprints 2857-2863 of 9728")
	)
	(layers
		(0 "F.Cu" signal "TOP")
		(4 "In1.Cu" signal "GND")
		(6 "In2.Cu" signal "VCC")
		(8 "In3.Cu" signal "VCC1")
		(10 "In4.Cu" signal "GND1")
		(12 "In5.Cu" signal "IN1")
		(14 "In6.Cu" signal "GND2")
		(16 "In7.Cu" signal "IN2")
		(18 "In8.Cu" signal "GND3")
		(20 "In9.Cu" signal "IN3")
		(22 "In10.Cu" signal "GND4")
		(24 "In11.Cu" signal "IN4")
		(26 "In12.Cu" signal "GND5")
		(28 "In13.Cu" signal "IN5")
		(30 "In14.Cu" signal "GND6")
		(32 "In15.Cu" signal "IN6")
		(34 "In16.Cu" signal "GND7")
		(2 "B.Cu" signal "BOTTOM")
		(9 "F.Adhes" user "F.Adhesive")
		(11 "B.Adhes" user "B.Adhesive")
		(13 "F.Paste" user "Package Geometry/Pastemask Top")
		(15 "B.Paste" user "Package Geometry/Pastemask Bottom")
		(5 "F.SilkS" user "Ref Des/Silkscreen Top")
		(7 "B.SilkS" user "Ref Des/Silkscreen Bottom")
		(1 "F.Mask" user "Board Geometry/Soldermask Top")
		(3 "B.Mask" user "Board Geometry/Soldermask Bottom")
		(17 "Dwgs.User" user "User.Drawings")
		(19 "Cmts.User" user "User.Comments")
		(21 "Eco1.User" user "User.Eco1")
		(23 "Eco2.User" user "User.Eco2")
		(25 "Edge.Cuts" user "Board Geometry/Outline")
		(27 "Margin" user)
		(31 "F.CrtYd" user "Package Geometry/Place Bound Top")
		(29 "B.CrtYd" user "Package Geometry/Place Bound Bottom")
		(35 "F.Fab" user "Ref Des/Assembly Top")
		(33 "B.Fab" user "Ref Des/Assembly Bottom")
	)
	(footprint ""
		(layer "F.Cu")
		(at 239.813338 -136.328404 180)
		(property "Reference" "PC312"
			(at 0 0 180)
			(layer "F.SilkS")
			(hide yes)
			(effects
				(font
					(size 1.27 1.27)
				)
			)
		)
		(property "Value" ""
			(at 0 0 180)
			(layer "F.Fab")
			(effects
				(font
					(size 1.27 1.27)
				)
			)
		)
		(duplicate_pad_numbers_are_jumpers no)
		(fp_line
			(start 0.7874 0.4064)
			(end -0.7874 0.4064)
			(stroke
				(width 0.1524)
				(type default)
			)
			(layer "F.SilkS")
		)
		(fp_line
			(start 0.7874 -0.4064)
			(end 0.7874 0.4064)
			(stroke
				(width 0.1524)
				(type default)
			)
			(layer "F.SilkS")
		)
		(fp_line
			(start -0.7874 0.4064)
			(end -0.7874 -0.4064)
			(stroke
				(width 0.1524)
				(type default)
			)
			(layer "F.SilkS")
		)
		(fp_line
			(start -0.7874 -0.4064)
			(end 0.7874 -0.4064)
			(stroke
				(width 0.1524)
				(type default)
			)
			(layer "F.SilkS")
		)
		(fp_line
			(start 0.67945 0.3048)
			(end 0.120396 0.3048)
			(stroke
				(width 0.1)
				(type default)
			)
			(layer "F.Fab")
		)
		(fp_line
			(start 0.67945 -0.3048)
			(end 0.67945 0.3048)
			(stroke
				(width 0.1)
				(type default)
			)
			(layer "F.Fab")
		)
		(fp_line
			(start 0.12065 -0.2794)
			(end 0.12065 -0.3048)
			(stroke
				(width 0.1)
				(type default)
			)
			(layer "F.Fab")
		)
		(fp_line
			(start 0.12065 -0.3048)
			(end 0.67945 -0.3048)
			(stroke
				(width 0.1)
				(type default)
			)
			(layer "F.Fab")
		)
		(fp_line
			(start 0.120396 0.3048)
			(end 0.120396 0.2794)
			(stroke
				(width 0.1)
				(type default)
			)
			(layer "F.Fab")
		)
		(fp_line
			(start 0.120396 0.2794)
			(end -0.12065 0.2794)
			(stroke
				(width 0.1)
				(type default)
			)
			(layer "F.Fab")
		)
		(fp_line
			(start -0.12065 0.3048)
			(end -0.67945 0.3048)
			(stroke
				(width 0.1)
				(type default)
			)
			(layer "F.Fab")
		)
		(fp_line
			(start -0.12065 0.2794)
			(end -0.12065 0.3048)
			(stroke
				(width 0.1)
				(type default)
			)
			(layer "F.Fab")
		)
		(fp_line
			(start -0.12065 -0.2794)
			(end 0.12065 -0.2794)
			(stroke
				(width 0.1)
				(type default)
			)
			(layer "F.Fab")
		)
		(fp_line
			(start -0.12065 -0.305054)
			(end -0.12065 -0.2794)
			(stroke
				(width 0.1)
				(type default)
			)
			(layer "F.Fab")
		)
		(fp_line
			(start -0.67945 0.3048)
			(end -0.67945 -0.305054)
			(stroke
				(width 0.1)
				(type default)
			)
			(layer "F.Fab")
		)
		(fp_line
			(start -0.67945 -0.305054)
			(end -0.12065 -0.305054)
			(stroke
				(width 0.1)
				(type default)
			)
			(layer "F.Fab")
		)
		(pad "1" smd circle
			(at -0.40005 0 180)
			(size 0 0)
			(layers "F.Cu" "F.Mask" "F.Paste")
			(net "P5V_AUX")
		)
		(pad "2" smd circle
			(at 0.40005 0 180)
			(size 0 0)
			(layers "F.Cu" "F.Mask" "F.Paste")
			(net "GND")
		)
	)
	(footprint ""
		(layer "F.Cu")
		(at 135.838692 -44.341542 90)
		(property "Reference" "C311"
			(at 0 0 90)
			(layer "F.SilkS")
			(hide yes)
			(effects
				(font
					(size 1.27 1.27)
				)
			)
		)
		(property "Value" ""
			(at 0 0 90)
			(layer "F.Fab")
			(effects
				(font
					(size 1.27 1.27)
				)
			)
		)
		(duplicate_pad_numbers_are_jumpers no)
		(fp_line
			(start 0.7874 -0.4064)
			(end 0.7874 0.4064)
			(stroke
				(width 0.1524)
				(type default)
			)
			(layer "F.SilkS")
		)
		(fp_line
			(start -0.7874 -0.4064)
			(end 0.7874 -0.4064)
			(stroke
				(width 0.1524)
				(type default)
			)
			(layer "F.SilkS")
		)
		(fp_line
			(start 0.7874 0.4064)
			(end -0.7874 0.4064)
			(stroke
				(width 0.1524)
				(type default)
			)
			(layer "F.SilkS")
		)
		(fp_line
			(start -0.7874 0.4064)
			(end -0.7874 -0.4064)
			(stroke
				(width 0.1524)
				(type default)
			)
			(layer "F.SilkS")
		)
		(fp_line
			(start -0.12065 -0.305054)
			(end -0.12065 -0.2794)
			(stroke
				(width 0.1)
				(type default)
			)
			(layer "F.Fab")
		)
		(fp_line
			(start -0.67945 -0.305054)
			(end -0.12065 -0.305054)
			(stroke
				(width 0.1)
				(type default)
			)
			(layer "F.Fab")
		)
		(fp_line
			(start 0.67945 -0.3048)
			(end 0.67945 0.3048)
			(stroke
				(width 0.1)
				(type default)
			)
			(layer "F.Fab")
		)
		(fp_line
			(start 0.12065 -0.3048)
			(end 0.67945 -0.3048)
			(stroke
				(width 0.1)
				(type default)
			)
			(layer "F.Fab")
		)
		(fp_line
			(start 0.12065 -0.2794)
			(end 0.12065 -0.3048)
			(stroke
				(width 0.1)
				(type default)
			)
			(layer "F.Fab")
		)
		(fp_line
			(start -0.12065 -0.2794)
			(end 0.12065 -0.2794)
			(stroke
				(width 0.1)
				(type default)
			)
			(layer "F.Fab")
		)
		(fp_line
			(start 0.120396 0.2794)
			(end -0.12065 0.2794)
			(stroke
				(width 0.1)
				(type default)
			)
			(layer "F.Fab")
		)
		(fp_line
			(start -0.12065 0.2794)
			(end -0.12065 0.3048)
			(stroke
				(width 0.1)
				(type default)
			)
			(layer "F.Fab")
		)
		(fp_line
			(start 0.67945 0.3048)
			(end 0.120396 0.3048)
			(stroke
				(width 0.1)
				(type default)
			)
			(layer "F.Fab")
		)
		(fp_line
			(start 0.120396 0.3048)
			(end 0.120396 0.2794)
			(stroke
				(width 0.1)
				(type default)
			)
			(layer "F.Fab")
		)
		(fp_line
			(start -0.12065 0.3048)
			(end -0.67945 0.3048)
			(stroke
				(width 0.1)
				(type default)
			)
			(layer "F.Fab")
		)
		(fp_line
			(start -0.67945 0.3048)
			(end -0.67945 -0.305054)
			(stroke
				(width 0.1)
				(type default)
			)
			(layer "F.Fab")
		)
		(pad "1" smd circle
			(at -0.40005 0 90)
			(size 0 0)
			(layers "F.Cu" "F.Mask" "F.Paste")
			(net "P12V_SSD4_VIN_P")
		)
		(pad "2" smd circle
			(at 0.40005 0 90)
			(size 0 0)
			(layers "F.Cu" "F.Mask" "F.Paste")
			(net "P12V_SSD4_VIN_N")
		)
	)
	(footprint ""
		(layer "F.Cu")
		(at 341.746586 -285.088584 90)
		(property "Reference" "PC137"
			(at 0 0 90)
			(layer "F.SilkS")
			(hide yes)
			(effects
				(font
					(size 1.27 1.27)
				)
			)
		)
		(property "Value" ""
			(at 0 0 90)
			(layer "F.Fab")
			(effects
				(font
					(size 1.27 1.27)
				)
			)
		)
		(duplicate_pad_numbers_are_jumpers no)
		(fp_line
			(start 0.7874 -0.4064)
			(end 0.7874 0.4064)
			(stroke
				(width 0.1524)
				(type default)
			)
			(layer "F.SilkS")
		)
		(fp_line
			(start -0.7874 -0.4064)
			(end 0.7874 -0.4064)
			(stroke
				(width 0.1524)
				(type default)
			)
			(layer "F.SilkS")
		)
		(fp_line
			(start 0.7874 0.4064)
			(end -0.7874 0.4064)
			(stroke
				(width 0.1524)
				(type default)
			)
			(layer "F.SilkS")
		)
		(fp_line
			(start -0.7874 0.4064)
			(end -0.7874 -0.4064)
			(stroke
				(width 0.1524)
				(type default)
			)
			(layer "F.SilkS")
		)
		(fp_line
			(start -0.12065 -0.305054)
			(end -0.12065 -0.2794)
			(stroke
				(width 0.1)
				(type default)
			)
			(layer "F.Fab")
		)
		(fp_line
			(start -0.67945 -0.305054)
			(end -0.12065 -0.305054)
			(stroke
				(width 0.1)
				(type default)
			)
			(layer "F.Fab")
		)
		(fp_line
			(start 0.67945 -0.3048)
			(end 0.67945 0.3048)
			(stroke
				(width 0.1)
				(type default)
			)
			(layer "F.Fab")
		)
		(fp_line
			(start 0.12065 -0.3048)
			(end 0.67945 -0.3048)
			(stroke
				(width 0.1)
				(type default)
			)
			(layer "F.Fab")
		)
		(fp_line
			(start 0.12065 -0.2794)
			(end 0.12065 -0.3048)
			(stroke
				(width 0.1)
				(type default)
			)
			(layer "F.Fab")
		)
		(fp_line
			(start -0.12065 -0.2794)
			(end 0.12065 -0.2794)
			(stroke
				(width 0.1)
				(type default)
			)
			(layer "F.Fab")
		)
		(fp_line
			(start 0.120396 0.2794)
			(end -0.12065 0.2794)
			(stroke
				(width 0.1)
				(type default)
			)
			(layer "F.Fab")
		)
		(fp_line
			(start -0.12065 0.2794)
			(end -0.12065 0.3048)
			(stroke
				(width 0.1)
				(type default)
			)
			(layer "F.Fab")
		)
		(fp_line
			(start 0.67945 0.3048)
			(end 0.120396 0.3048)
			(stroke
				(width 0.1)
				(type default)
			)
			(layer "F.Fab")
		)
		(fp_line
			(start 0.120396 0.3048)
			(end 0.120396 0.2794)
			(stroke
				(width 0.1)
				(type default)
			)
			(layer "F.Fab")
		)
		(fp_line
			(start -0.12065 0.3048)
			(end -0.67945 0.3048)
			(stroke
				(width 0.1)
				(type default)
			)
			(layer "F.Fab")
		)
		(fp_line
			(start -0.67945 0.3048)
			(end -0.67945 -0.305054)
			(stroke
				(width 0.1)
				(type default)
			)
			(layer "F.Fab")
		)
		(pad "1" smd circle
			(at -0.40005 0 90)
			(size 0 0)
			(layers "F.Cu" "F.Mask" "F.Paste")
			(net "P0V8_PEX2_PVCC")
		)
		(pad "2" smd circle
			(at 0.40005 0 90)
			(size 0 0)
			(layers "F.Cu" "F.Mask" "F.Paste")
			(net "GND")
		)
	)
	(footprint ""
		(layer "F.Cu")
		(at 400.05762 -356.244906 90)
		(property "Reference" "C749"
			(at 0 0 90)
			(layer "F.SilkS")
			(hide yes)
			(effects
				(font
					(size 1.27 1.27)
				)
			)
		)
		(property "Value" ""
			(at 0 0 90)
			(layer "F.Fab")
			(effects
				(font
					(size 1.27 1.27)
				)
			)
		)
		(duplicate_pad_numbers_are_jumpers no)
		(fp_line
			(start 0.299974 -0.150114)
			(end 0.299974 0.150114)
			(stroke
				(width 0.1)
				(type default)
			)
			(layer "F.Fab")
		)
		(fp_line
			(start -0.299974 -0.150114)
			(end 0.299974 -0.150114)
			(stroke
				(width 0.1)
				(type default)
			)
			(layer "F.Fab")
		)
		(fp_line
			(start 0.299974 0.150114)
			(end -0.299974 0.150114)
			(stroke
				(width 0.1)
				(type default)
			)
			(layer "F.Fab")
		)
		(fp_line
			(start -0.299974 0.150114)
			(end -0.299974 -0.150114)
			(stroke
				(width 0.1)
				(type default)
			)
			(layer "F.Fab")
		)
		(pad "1" smd rect
			(at -0.2667 0 90)
			(size 0.3048 0.381)
			(layers "F.Cu" "F.Mask" "F.Paste")
			(net "P5E_PEX3_STN5_TX_DN<86>")
		)
		(pad "2" smd rect
			(at 0.2667 0 90)
			(size 0.3048 0.381)
			(layers "F.Cu" "F.Mask" "F.Paste")
			(net "P5E_PEX3_STN5_TX_C_DN<86>")
		)
	)
	(footprint ""
		(layer "F.Cu")
		(at 174.164244 -139.6238)
		(property "Reference" "R139"
			(at 0 0 0)
			(layer "F.SilkS")
			(hide yes)
			(effects
				(font
					(size 1.27 1.27)
				)
			)
		)
		(property "Value" ""
			(at 0 0 0)
			(layer "F.Fab")
			(effects
				(font
					(size 1.27 1.27)
				)
			)
		)
		(duplicate_pad_numbers_are_jumpers no)
		(fp_line
			(start -0.7874 -0.4064)
			(end 0.7874 -0.4064)
			(stroke
				(width 0.1524)
				(type default)
			)
			(layer "F.SilkS")
		)
		(fp_line
			(start -0.7874 0.4064)
			(end -0.7874 -0.4064)
			(stroke
				(width 0.1524)
				(type default)
			)
			(layer "F.SilkS")
		)
		(fp_line
			(start 0.7874 -0.4064)
			(end 0.7874 0.4064)
			(stroke
				(width 0.1524)
				(type default)
			)
			(layer "F.SilkS")
		)
		(fp_line
			(start 0.7874 0.4064)
			(end -0.7874 0.4064)
			(stroke
				(width 0.1524)
				(type default)
			)
			(layer "F.SilkS")
		)
		(fp_line
			(start -0.67945 -0.305054)
			(end -0.12065 -0.305054)
			(stroke
				(width 0.1)
				(type default)
			)
			(layer "F.Fab")
		)
		(fp_line
			(start -0.67945 0.3048)
			(end -0.67945 -0.305054)
			(stroke
				(width 0.1)
				(type default)
			)
			(layer "F.Fab")
		)
		(fp_line
			(start -0.12065 -0.305054)
			(end -0.12065 -0.2794)
			(stroke
				(width 0.1)
				(type default)
			)
			(layer "F.Fab")
		)
		(fp_line
			(start -0.12065 -0.2794)
			(end 0.12065 -0.2794)
			(stroke
				(width 0.1)
				(type default)
			)
			(layer "F.Fab")
		)
		(fp_line
			(start -0.12065 0.2794)
			(end -0.12065 0.3048)
			(stroke
				(width 0.1)
				(type default)
			)
			(layer "F.Fab")
		)
		(fp_line
			(start -0.12065 0.3048)
			(end -0.67945 0.3048)
			(stroke
				(width 0.1)
				(type default)
			)
			(layer "F.Fab")
		)
		(fp_line
			(start 0.120396 0.2794)
			(end -0.12065 0.2794)
			(stroke
				(width 0.1)
				(type default)
			)
			(layer "F.Fab")
		)
		(fp_line
			(start 0.120396 0.3048)
			(end 0.120396 0.2794)
			(stroke
				(width 0.1)
				(type default)
			)
			(layer "F.Fab")
		)
		(fp_line
			(start 0.12065 -0.3048)
			(end 0.67945 -0.3048)
			(stroke
				(width 0.1)
				(type default)
			)
			(layer "F.Fab")
		)
		(fp_line
			(start 0.12065 -0.2794)
			(end 0.12065 -0.3048)
			(stroke
				(width 0.1)
				(type default)
			)
			(layer "F.Fab")
		)
		(fp_line
			(start 0.67945 -0.3048)
			(end 0.67945 0.3048)
			(stroke
				(width 0.1)
				(type default)
			)
			(layer "F.Fab")
		)
		(fp_line
			(start 0.67945 0.3048)
			(end 0.120396 0.3048)
			(stroke
				(width 0.1)
				(type default)
			)
			(layer "F.Fab")
		)
		(pad "1" smd circle
			(at -0.40005 0)
			(size 0 0)
			(layers "F.Cu" "F.Mask" "F.Paste")
			(net "RST_SMB_NIC2_MUX_ISO_R_N")
		)
		(pad "2" smd circle
			(at 0.40005 0)
			(size 0 0)
			(layers "F.Cu" "F.Mask" "F.Paste")
			(net "RST_SMB_NIC2_MUX_ISO_N")
		)
	)
	(footprint ""
		(layer "F.Cu")
		(at 396.859252 -166.55288)
		(property "Reference" "U40"
			(at -2.041652 1.86055 0)
			(unlocked yes)
			(layer "F.SilkS")
			(effects
				(font
					(size 0.7874 0.5842)
					(thickness 0.1524)
				)
				(justify left)
			)
		)
		(property "Value" ""
			(at 0 0 0)
			(layer "F.Fab")
			(effects
				(font
					(size 1.27 1.27)
				)
			)
		)
		(duplicate_pad_numbers_are_jumpers no)
		(fp_line
			(start -1.684274 -1.074928)
			(end -0.381 -1.074928)
			(stroke
				(width 0.1524)
				(type default)
			)
			(layer "F.SilkS")
		)
		(fp_line
			(start -1.684274 1.074928)
			(end -1.684274 -1.074928)
			(stroke
				(width 0.1524)
				(type default)
			)
			(layer "F.SilkS")
		)
		(fp_line
			(start -0.381 -1.074928)
			(end 0 -0.625094)
			(stroke
				(width 0.1524)
				(type default)
			)
			(layer "F.SilkS")
		)
		(fp_line
			(start 0 -0.625094)
			(end 0.381 -1.074928)
			(stroke
				(width 0.1524)
				(type default)
			)
			(layer "F.SilkS")
		)
		(fp_line
			(start 0.381 -1.074928)
			(end 1.684274 -1.074928)
			(stroke
				(width 0.1524)
				(type default)
			)
			(layer "F.SilkS")
		)
		(fp_line
			(start 1.684274 -1.074928)
			(end 1.684274 1.074928)
			(stroke
				(width 0.1524)
				(type default)
			)
			(layer "F.SilkS")
		)
		(fp_line
			(start 1.684274 1.074928)
			(end -1.684274 1.074928)
			(stroke
				(width 0.1524)
				(type default)
			)
			(layer "F.SilkS")
		)
		(fp_poly
			(pts
				(xy -2.637282 -0.903986) (xy -2.637282 -0.395986) (xy -1.875282 -0.649986)
			)
			(stroke
				(width 0)
				(type default)
			)
			(fill yes)
			(layer "F.SilkS")
		)
		(fp_line
			(start -0.700024 -1.074928)
			(end -0.700024 1.074928)
			(stroke
				(width 0.1)
				(type default)
			)
			(layer "F.Fab")
		)
		(fp_line
			(start -0.700024 1.074928)
			(end 0.700024 1.074928)
			(stroke
				(width 0.1)
				(type default)
			)
			(layer "F.Fab")
		)
		(fp_line
			(start 0.700024 -1.074928)
			(end -0.700024 -1.074928)
			(stroke
				(width 0.1)
				(type default)
			)
			(layer "F.Fab")
		)
		(fp_line
			(start 0.700024 1.074928)
			(end 0.700024 -1.074928)
			(stroke
				(width 0.1)
				(type default)
			)
			(layer "F.Fab")
		)
		(fp_poly
			(pts
				(xy -2.637282 -0.903986) (xy -2.637282 -0.395986) (xy -1.875282 -0.649986)
			)
			(stroke
				(width 0)
				(type default)
			)
			(fill yes)
			(layer "F.Fab")
		)
		(pad "1" smd rect
			(at -1.100074 -0.649986 270)
			(size 0.4064 0.9144)
			(layers "F.Cu" "F.Mask" "F.Paste")
			(net "Net_8450")
		)
		(pad "2" smd rect
			(at -1.100074 0 270)
			(size 0.4064 0.9144)
			(layers "F.Cu" "F.Mask" "F.Paste")
			(net "RST_HP_NIC6_N")
		)
		(pad "3" smd rect
			(at -1.100074 0.649986 270)
			(size 0.4064 0.9144)
			(layers "F.Cu" "F.Mask" "F.Paste")
			(net "GND")
		)
		(pad "4" smd rect
			(at 1.100074 0.649986 270)
			(size 0.4064 0.9144)
			(layers "F.Cu" "F.Mask" "F.Paste")
			(net "RST_HP_NIC6_BUF_N")
		)
		(pad "5" smd rect
			(at 1.100074 -0.649986 270)
			(size 0.4064 0.9144)
			(layers "F.Cu" "F.Mask" "F.Paste")
			(net "P3V3_AUX")
		)
	)
	(footprint ""
		(layer "F.Cu")
		(at 220.34373 -46.90491)
		(property "Reference" "R587"
			(at 0 0 0)
			(layer "F.SilkS")
			(hide yes)
			(effects
				(font
					(size 1.27 1.27)
				)
			)
		)
		(property "Value" ""
			(at 0 0 0)
			(layer "F.Fab")
			(effects
				(font
					(size 1.27 1.27)
				)
			)
		)
		(duplicate_pad_numbers_are_jumpers no)
		(fp_line
			(start -0.7874 -0.4064)
			(end 0.7874 -0.4064)
			(stroke
				(width 0.1524)
				(type default)
			)
			(layer "F.SilkS")
		)
		(fp_line
			(start -0.7874 0.4064)
			(end -0.7874 -0.4064)
			(stroke
				(width 0.1524)
				(type default)
			)
			(layer "F.SilkS")
		)
		(fp_line
			(start 0.7874 -0.4064)
			(end 0.7874 0.4064)
			(stroke
				(width 0.1524)
				(type default)
			)
			(layer "F.SilkS")
		)
		(fp_line
			(start 0.7874 0.4064)
			(end -0.7874 0.4064)
			(stroke
				(width 0.1524)
				(type default)
			)
			(layer "F.SilkS")
		)
		(fp_line
			(start -0.67945 -0.305054)
			(end -0.12065 -0.305054)
			(stroke
				(width 0.1)
				(type default)
			)
			(layer "F.Fab")
		)
		(fp_line
			(start -0.67945 0.3048)
			(end -0.67945 -0.305054)
			(stroke
				(width 0.1)
				(type default)
			)
			(layer "F.Fab")
		)
		(fp_line
			(start -0.12065 -0.305054)
			(end -0.12065 -0.2794)
			(stroke
				(width 0.1)
				(type default)
			)
			(layer "F.Fab")
		)
		(fp_line
			(start -0.12065 -0.2794)
			(end 0.12065 -0.2794)
			(stroke
				(width 0.1)
				(type default)
			)
			(layer "F.Fab")
		)
		(fp_line
			(start -0.12065 0.2794)
			(end -0.12065 0.3048)
			(stroke
				(width 0.1)
				(type default)
			)
			(layer "F.Fab")
		)
		(fp_line
			(start -0.12065 0.3048)
			(end -0.67945 0.3048)
			(stroke
				(width 0.1)
				(type default)
			)
			(layer "F.Fab")
		)
		(fp_line
			(start 0.120396 0.2794)
			(end -0.12065 0.2794)
			(stroke
				(width 0.1)
				(type default)
			)
			(layer "F.Fab")
		)
		(fp_line
			(start 0.120396 0.3048)
			(end 0.120396 0.2794)
			(stroke
				(width 0.1)
				(type default)
			)
			(layer "F.Fab")
		)
		(fp_line
			(start 0.12065 -0.3048)
			(end 0.67945 -0.3048)
			(stroke
				(width 0.1)
				(type default)
			)
			(layer "F.Fab")
		)
		(fp_line
			(start 0.12065 -0.2794)
			(end 0.12065 -0.3048)
			(stroke
				(width 0.1)
				(type default)
			)
			(layer "F.Fab")
		)
		(fp_line
			(start 0.67945 -0.3048)
			(end 0.67945 0.3048)
			(stroke
				(width 0.1)
				(type default)
			)
			(layer "F.Fab")
		)
		(fp_line
			(start 0.67945 0.3048)
			(end 0.120396 0.3048)
			(stroke
				(width 0.1)
				(type default)
			)
			(layer "F.Fab")
		)
		(pad "1" smd circle
			(at -0.40005 0)
			(size 0 0)
			(layers "F.Cu" "F.Mask" "F.Paste")
			(net "SSD7_ADC_ALERT_N")
		)
		(pad "2" smd circle
			(at 0.40005 0)
			(size 0 0)
			(layers "F.Cu" "F.Mask" "F.Paste")
			(net "SSD_0_7_ADC_ALERT_N")
		)
	)
)
